# BASEBOARD_FAB2 (Tioga Pass) — schematic netlist excerpt (pin names and nets, part order shuffled) for the footprints in the layout excerpt that follows; sources: Cadence DE-HDL packaged netlist, KiCad conversion of Wiwynn_Tioga_Pass_MB.brd

R2T2  RES  0.0 5% CHIP  pkg 0402  page 154 : A = SPI_PCH_IO3 ; B = SPI_PCH_IO3_R1
R8F3  RES  2.2 5% EMPTY  pkg 0402  page 240 : A = VR_P3V3_STBY_SNUB ; B = GND
R7C17  RES  4.75K 1% CHIP  pkg 0402  page 166 : A = PVCCIO_CPU0 ; B = PECI_BMC

(kicad_pcb
	(version 20260206)
	(generator "pcbnew")
	(generator_version "10.0")
	(general
		(thickness 1.6)
		(legacy_teardrops no)
	)
	(paper "A4")
	(title_block
		(title "Wiwynn_Tioga_Pass_MB.brd")
		(comment 1 "Tioga Pass / footprints 3305-3307 of 4770")
	)
	(layers
		(0 "F.Cu" signal "TOP")
		(4 "In1.Cu" signal "L2GND")
		(6 "In2.Cu" signal "L3")
		(8 "In3.Cu" signal "L4GND")
		(10 "In4.Cu" signal "L5")
		(12 "In5.Cu" signal "L6GND")
		(14 "In6.Cu" signal "L7VCC")
		(16 "In7.Cu" signal "L8VCC")
		(18 "In8.Cu" signal "L9GND")
		(20 "In9.Cu" signal "L10")
		(22 "In10.Cu" signal "L11GND")
		(24 "In11.Cu" signal "L12")
		(26 "In12.Cu" signal "L13GND")
		(2 "B.Cu" signal "BOTTOM")
		(9 "F.Adhes" user "F.Adhesive")
		(11 "B.Adhes" user "B.Adhesive")
		(13 "F.Paste" user "Package Geometry/Pastemask Top")
		(15 "B.Paste" user "Package Geometry/Pastemask Bottom")
		(5 "F.SilkS" user "Ref Des/Silkscreen Top")
		(7 "B.SilkS" user "Ref Des/Silkscreen Bottom")
		(1 "F.Mask" user "Board Geometry/Soldermask Top")
		(3 "B.Mask" user "Board Geometry/Soldermask Bottom")
		(17 "Dwgs.User" user "User.Drawings")
		(19 "Cmts.User" user "User.Comments")
		(21 "Eco1.User" user "User.Eco1")
		(23 "Eco2.User" user "User.Eco2")
		(25 "Edge.Cuts" user "Board Geometry/Outline")
		(27 "Margin" user)
		(31 "F.CrtYd" user "Package Geometry/Place Bound Top")
		(29 "B.CrtYd" user "Package Geometry/Place Bound Bottom")
		(35 "F.Fab" user "Ref Des/Assembly Top")
		(33 "B.Fab" user "Ref Des/Assembly Bottom")
	)
	(footprint ""
		(layer "B.Cu")
		(at 473.973906 -19.948398 -90)
		(property "Reference" "R8F3"
			(at 0 0 90)
			(layer "B.SilkS")
			(hide yes)
			(effects
				(font
					(size 1.27 1.27)
				)
				(justify mirror)
			)
		)
		(property "Value" ""
			(at 0 0 90)
			(layer "B.Fab")
			(effects
				(font
					(size 1.27 1.27)
				)
				(justify mirror)
			)
		)
		(duplicate_pad_numbers_are_jumpers no)
		(fp_rect
			(start -0.2794 -0.1016)
			(end 0.2794 0.9906)
			(stroke
				(width 0)
				(type default)
			)
			(fill no)
			(layer "B.CrtYd")
		)
		(fp_line
			(start -0.2794 0.9906)
			(end -0.2794 -0.1016)
			(stroke
				(width 0.1)
				(type default)
			)
			(layer "B.Fab")
		)
		(fp_line
			(start 0.2794 0.9906)
			(end -0.2794 0.9906)
			(stroke
				(width 0.1)
				(type default)
			)
			(layer "B.Fab")
		)
		(fp_line
			(start -0.2794 -0.1016)
			(end 0.2794 -0.1016)
			(stroke
				(width 0.1)
				(type default)
			)
			(layer "B.Fab")
		)
		(fp_line
			(start 0.2794 -0.1016)
			(end 0.2794 0.9906)
			(stroke
				(width 0.1)
				(type default)
			)
			(layer "B.Fab")
		)
		(pad "1" smd rect
			(at 0 0 90)
			(size 0.508 0.508)
			(layers "B.Cu" "B.Mask" "B.Paste")
			(net "VR_P3V3_STBY_SNUB")
		)
		(pad "2" smd rect
			(at 0 0.889 90)
			(size 0.508 0.508)
			(layers "B.Cu" "B.Mask" "B.Paste")
			(net "GND")
		)
		(zone
			(layer "B.Cu")
			(hatch none 0.5)
			(connect_pads
				(clearance 0)
			)
			(min_thickness 0.25)
			(keepout
				(tracks allowed)
				(vias not_allowed)
				(pads allowed)
				(copperpour not_allowed)
				(footprints allowed)
			)
			(placement
				(enabled no)
				(sheetname "")
			)
			(fill
				(thermal_gap 0.5)
				(thermal_bridge_width 0.5)
				(island_removal_mode 0)
			)
			(polygon
				(pts
					(xy 473.719906 -20.202398) (xy 473.338906 -20.202398) (xy 473.338906 -19.694398) (xy 473.719906 -19.694398)
				)
			)
		)
		(zone
			(layer "B.Cu")
			(hatch none 0.5)
			(connect_pads
				(clearance 0)
			)
			(min_thickness 0.25)
			(keepout
				(tracks not_allowed)
				(vias allowed)
				(pads allowed)
				(copperpour not_allowed)
				(footprints allowed)
			)
			(placement
				(enabled no)
				(sheetname "")
			)
			(fill
				(thermal_gap 0.5)
				(thermal_bridge_width 0.5)
				(island_removal_mode 0)
			)
			(polygon
				(pts
					(xy 473.719906 -20.202398) (xy 473.338906 -20.202398) (xy 473.338906 -19.694398) (xy 473.719906 -19.694398)
				)
			)
		)
	)
	(footprint ""
		(layer "B.Cu")
		(at 385.778248 -58.809128 -90)
		(property "Reference" "R2T2"
			(at 0 0 90)
			(layer "B.SilkS")
			(hide yes)
			(effects
				(font
					(size 1.27 1.27)
				)
				(justify mirror)
			)
		)
		(property "Value" ""
			(at 0 0 90)
			(layer "B.Fab")
			(effects
				(font
					(size 1.27 1.27)
				)
				(justify mirror)
			)
		)
		(duplicate_pad_numbers_are_jumpers no)
		(fp_poly
			(pts
				(xy 0.2794 -0.1016) (xy -0.2794 -0.1016) (xy -0.2794 0.9906) (xy 0.2794 0.9906)
			)
			(stroke
				(width 0)
				(type default)
			)
			(fill no)
			(layer "B.CrtYd")
		)
		(fp_line
			(start -0.2794 0.9906)
			(end -0.2794 -0.1016)
			(stroke
				(width 0.1)
				(type default)
			)
			(layer "B.Fab")
		)
		(fp_line
			(start 0.2794 0.9906)
			(end -0.2794 0.9906)
			(stroke
				(width 0.1)
				(type default)
			)
			(layer "B.Fab")
		)
		(fp_line
			(start -0.2794 -0.1016)
			(end 0.2794 -0.1016)
			(stroke
				(width 0.1)
				(type default)
			)
			(layer "B.Fab")
		)
		(fp_line
			(start 0.2794 -0.1016)
			(end 0.2794 0.9906)
			(stroke
				(width 0.1)
				(type default)
			)
			(layer "B.Fab")
		)
		(pad "1" smd rect
			(at 0 0 90)
			(size 0.508 0.508)
			(layers "B.Cu" "B.Mask" "B.Paste")
			(net "SPI_PCH_IO3")
		)
		(pad "2" smd rect
			(at 0 0.889 90)
			(size 0.508 0.508)
			(layers "B.Cu" "B.Mask" "B.Paste")
			(net "SPI_PCH_IO3_R1")
		)
		(zone
			(layer "B.Cu")
			(hatch none 0.5)
			(connect_pads
				(clearance 0)
			)
			(min_thickness 0.25)
			(keepout
				(tracks not_allowed)
				(vias allowed)
				(pads allowed)
				(copperpour not_allowed)
				(footprints allowed)
			)
			(placement
				(enabled no)
				(sheetname "")
			)
			(fill
				(thermal_gap 0.5)
				(thermal_bridge_width 0.5)
				(island_removal_mode 0)
			)
			(polygon
				(pts
					(xy 385.143248 -58.555128) (xy 385.143248 -59.063128) (xy 385.524248 -59.063128) (xy 385.524248 -58.555128)
				)
			)
		)
		(zone
			(layer "B.Cu")
			(hatch none 0.5)
			(connect_pads
				(clearance 0)
			)
			(min_thickness 0.25)
			(keepout
				(tracks allowed)
				(vias not_allowed)
				(pads allowed)
				(copperpour not_allowed)
				(footprints allowed)
			)
			(placement
				(enabled no)
				(sheetname "")
			)
			(fill
				(thermal_gap 0.5)
				(thermal_bridge_width 0.5)
				(island_removal_mode 0)
			)
			(polygon
				(pts
					(xy 385.524248 -58.555128) (xy 385.524248 -59.063128) (xy 385.143248 -59.063128) (xy 385.143248 -58.555128)
				)
			)
		)
	)
	(footprint ""
		(layer "B.Cu")
		(at 378.587 -86.233)
		(property "Reference" "R7C17"
			(at 0.8382 -0.67818 0)
			(unlocked yes)
			(layer "B.SilkS")
			(effects
				(font
					(size 0.4064 0.254)
					(thickness 0.1524)
				)
				(justify left mirror)
			)
		)
		(property "Value" ""
			(at 0 0 0)
			(layer "B.Fab")
			(effects
				(font
					(size 1.27 1.27)
				)
				(justify mirror)
			)
		)
		(duplicate_pad_numbers_are_jumpers no)
		(fp_poly
			(pts
				(xy 0.2794 -0.1016) (xy -0.2794 -0.1016) (xy -0.2794 0.9906) (xy 0.2794 0.9906)
			)
			(stroke
				(width 0)
				(type default)
			)
			(fill no)
			(layer "B.CrtYd")
		)
		(fp_line
			(start -0.2794 -0.1016)
			(end 0.2794 -0.1016)
			(stroke
				(width 0.1)
				(type default)
			)
			(layer "B.Fab")
		)
		(fp_line
			(start -0.2794 0.9906)
			(end -0.2794 -0.1016)
			(stroke
				(width 0.1)
				(type default)
			)
			(layer "B.Fab")
		)
		(fp_line
			(start 0.2794 -0.1016)
			(end 0.2794 0.9906)
			(stroke
				(width 0.1)
				(type default)
			)
			(layer "B.Fab")
		)
		(fp_line
			(start 0.2794 0.9906)
			(end -0.2794 0.9906)
			(stroke
				(width 0.1)
				(type default)
			)
			(layer "B.Fab")
		)
		(pad "1" smd rect
			(at 0 0 180)
			(size 0.508 0.508)
			(layers "B.Cu" "B.Mask" "B.Paste")
			(net "PVCCIO_CPU0")
		)
		(pad "2" smd rect
			(at 0 0.889 180)
			(size 0.508 0.508)
			(layers "B.Cu" "B.Mask" "B.Paste")
			(net "PECI_BMC")
		)
		(zone
			(layer "B.Cu")
			(hatch none 0.5)
			(connect_pads
				(clearance 0)
			)
			(min_thickness 0.25)
			(keepout
				(tracks allowed)
				(vias not_allowed)
				(pads allowed)
				(copperpour not_allowed)
				(footprints allowed)
			)
			(placement
				(enabled no)
				(sheetname "")
			)
			(fill
				(thermal_gap 0.5)
				(thermal_bridge_width 0.5)
				(island_removal_mode 0)
			)
			(polygon
				(pts
					(xy 378.841 -85.979) (xy 378.333 -85.979) (xy 378.333 -85.598) (xy 378.841 -85.598)
				)
			)
		)
		(zone
			(layer "B.Cu")
			(hatch none 0.5)
			(connect_pads
				(clearance 0)
			)
			(min_thickness 0.25)
			(keepout
				(tracks not_allowed)
				(vias allowed)
				(pads allowed)
				(copperpour not_allowed)
				(footprints allowed)
			)
			(placement
				(enabled no)
				(sheetname "")
			)
			(fill
				(thermal_gap 0.5)
				(thermal_bridge_width 0.5)
				(island_removal_mode 0)
			)
			(polygon
				(pts
					(xy 378.841 -85.598) (xy 378.333 -85.598) (xy 378.333 -85.979) (xy 378.841 -85.979)
				)
			)
		)
	)
)
